(kicad_pcb
	(version 20260206)
	(generator "pcbnew")
	(generator_version "10.0")
	(general
		(thickness 1.6)
		(legacy_teardrops no)
	)
	(paper "A4")
	(title_block
		(title "Bryce Canyon_SCC_16316-1_OCP.brd")
		(comment 1 "Bryce Canyon / footprints 474-479 of 1561")
	)
	(layers
		(0 "F.Cu" signal "TOP")
		(4 "In1.Cu" signal "L2GND")
		(6 "In2.Cu" signal "L3")
		(8 "In3.Cu" signal "L4VCC")
		(10 "In4.Cu" signal "L5VCC")
		(12 "In5.Cu" signal "L6")
		(14 "In6.Cu" signal "L7GND")
		(2 "B.Cu" signal "BOTTOM")
		(9 "F.Adhes" user "F.Adhesive")
		(11 "B.Adhes" user "B.Adhesive")
		(13 "F.Paste" user "Package Geometry/Pastemask Top")
		(15 "B.Paste" user "Package Geometry/Pastemask Bottom")
		(5 "F.SilkS" user "Ref Des/Silkscreen Top")
		(7 "B.SilkS" user "Ref Des/Silkscreen Bottom")
		(1 "F.Mask" user "Board Geometry/Soldermask Top")
		(3 "B.Mask" user "Board Geometry/Soldermask Bottom")
		(17 "Dwgs.User" user "User.Drawings")
		(19 "Cmts.User" user "User.Comments")
		(21 "Eco1.User" user "User.Eco1")
		(23 "Eco2.User" user "User.Eco2")
		(25 "Edge.Cuts" user "Board Geometry/Outline")
		(27 "Margin" user)
		(31 "F.CrtYd" user "Package Geometry/Place Bound Top")
		(29 "B.CrtYd" user "Package Geometry/Place Bound Bottom")
		(35 "F.Fab" user "Ref Des/Assembly Top")
		(33 "B.Fab" user "Ref Des/Assembly Bottom")
	)
	(footprint ""
		(layer "F.Cu")
		(at 147.470114 -40.80891 102)
		(property "Reference" "C333"
			(at 0 0 102)
			(layer "F.SilkS")
			(hide yes)
			(effects
				(font
					(size 1.27 1.27)
				)
			)
		)
		(property "Value" "SCD01U16V1KX-GP"
			(at -2.832048 -1.739777 102)
			(unlocked yes)
			(layer "F.Fab")
			(hide yes)
			(effects
				(font
					(size 1.016 1.016)
					(thickness 0.1524)
				)
			)
		)
		(property "Device Type" "C0201H13"
			(at -2.831925 -3.263781 102)
			(unlocked yes)
			(layer "F.Fab")
			(hide yes)
			(effects
				(font
					(size 1.016 1.016)
					(thickness 0.1524)
				)
			)
		)
		(duplicate_pad_numbers_are_jumpers no)
		(fp_poly
			(pts
				(xy -0.279454 -0.647706) (xy 0.279346 -0.647706) (xy 0.279346 0.647694) (xy -0.279454 0.647694)
			)
			(stroke
				(width 0)
				(type default)
			)
			(fill no)
			(layer "F.CrtYd")
		)
		(fp_poly
			(pts
				(xy -0.279454 -0.647706) (xy 0.279346 -0.647706) (xy 0.279346 0.647694) (xy -0.279454 0.647694)
			)
			(stroke
				(width 0)
				(type default)
			)
			(fill no)
			(layer "F.Fab")
		)
		(pad "1" smd custom
			(at -0.000001 -0.2794 102)
			(size 0.0762 0.0762)
			(layers "F.Cu" "F.Mask" "F.Paste")
			(net "PHY_SCC_TO_IOC_43_DP")
			(options
				(clearance outline)
				(anchor circle)
			)
			(primitives
				(gr_poly
					(pts
						(arc
							(start 0.1524 -0.127)
							(mid 0.137521 -0.162921)
							(end 0.1016 -0.1778)
						)
						(arc
							(start -0.1016 -0.1778)
							(mid -0.137521 -0.162921)
							(end -0.1524 -0.127)
						)
						(arc
							(start -0.1524 0.127)
							(mid -0.137521 0.162921)
							(end -0.1016 0.1778)
						)
						(arc
							(start 0.1016 0.1778)
							(mid 0.137521 0.162921)
							(end 0.1524 0.127)
						)
					)
					(width 0)
					(fill yes)
				)
			)
		)
		(pad "2" smd custom
			(at 0.000001 0.2794 102)
			(size 0.0762 0.0762)
			(layers "F.Cu" "F.Mask" "F.Paste")
			(net "PHY_SCC_TO_IOC_C_43_DP")
			(options
				(clearance outline)
				(anchor circle)
			)
			(primitives
				(gr_poly
					(pts
						(arc
							(start 0.1524 -0.127)
							(mid 0.137521 -0.162921)
							(end 0.1016 -0.1778)
						)
						(arc
							(start -0.1016 -0.1778)
							(mid -0.137521 -0.162921)
							(end -0.1524 -0.127)
						)
						(arc
							(start -0.1524 0.127)
							(mid -0.137521 0.162921)
							(end -0.1016 0.1778)
						)
						(arc
							(start 0.1016 0.1778)
							(mid 0.137521 0.162921)
							(end 0.1524 0.127)
						)
					)
					(width 0)
					(fill yes)
				)
			)
		)
	)
	(footprint ""
		(layer "F.Cu")
		(at 66.421 -104.6734 90)
		(property "Reference" "R501"
			(at 0 0 90)
			(layer "F.SilkS")
			(hide yes)
			(effects
				(font
					(size 1.27 1.27)
				)
			)
		)
		(property "Value" "19K6R2F-GP"
			(at 0.064008 -3.993896 90)
			(unlocked yes)
			(layer "F.Fab")
			(hide yes)
			(effects
				(font
					(size 1.016 1.016)
					(thickness 0.1524)
				)
			)
		)
		(property "Device Type" "R402H16"
			(at 0.064008 -5.517896 90)
			(unlocked yes)
			(layer "F.Fab")
			(hide yes)
			(effects
				(font
					(size 1.016 1.016)
					(thickness 0.1524)
				)
			)
		)
		(duplicate_pad_numbers_are_jumpers no)
		(fp_line
			(start 0.508 -0.9398)
			(end -0.508 -0.9398)
			(stroke
				(width 0.1524)
				(type default)
			)
			(layer "F.SilkS")
		)
		(fp_line
			(start -0.508 -0.9398)
			(end -0.508 0.9398)
			(stroke
				(width 0.1524)
				(type default)
			)
			(layer "F.SilkS")
		)
		(fp_rect
			(start -0.508 0.9398)
			(end 0.508 -0.9398)
			(stroke
				(width 0)
				(type default)
			)
			(fill no)
			(layer "F.CrtYd")
		)
		(fp_rect
			(start -0.508 0.9398)
			(end 0.508 -0.9398)
			(stroke
				(width 0)
				(type default)
			)
			(fill no)
			(layer "F.Fab")
		)
		(pad "1" smd custom
			(at 0 -0.4445 90)
			(size 0.1397 0.1397)
			(layers "F.Cu" "F.Mask" "F.Paste")
			(net "SCC_STBY_PGOOD_BUF")
			(options
				(clearance outline)
				(anchor circle)
			)
			(primitives
				(gr_poly
					(pts
						(arc
							(start -0.1778 -0.2794)
							(mid -0.249642 -0.249642)
							(end -0.2794 -0.1778)
						)
						(arc
							(start -0.2794 0.1778)
							(mid -0.249642 0.249642)
							(end -0.1778 0.2794)
						)
						(arc
							(start 0.1778 0.2794)
							(mid 0.249642 0.249642)
							(end 0.2794 0.1778)
						)
						(arc
							(start 0.2794 -0.1778)
							(mid 0.249642 -0.249642)
							(end 0.1778 -0.2794)
						)
					)
					(width 0)
					(fill yes)
				)
			)
		)
		(pad "2" smd custom
			(at 0 0.4445 90)
			(size 0.1397 0.1397)
			(layers "F.Cu" "F.Mask" "F.Paste")
			(net "GND")
			(options
				(clearance outline)
				(anchor circle)
			)
			(primitives
				(gr_poly
					(pts
						(arc
							(start -0.1778 -0.2794)
							(mid -0.249642 -0.249642)
							(end -0.2794 -0.1778)
						)
						(arc
							(start -0.2794 0.1778)
							(mid -0.249642 0.249642)
							(end -0.1778 0.2794)
						)
						(arc
							(start 0.1778 0.2794)
							(mid 0.249642 0.249642)
							(end 0.2794 0.1778)
						)
						(arc
							(start 0.2794 -0.1778)
							(mid 0.249642 -0.249642)
							(end 0.1778 -0.2794)
						)
					)
					(width 0)
					(fill yes)
				)
			)
		)
	)
	(footprint ""
		(layer "F.Cu")
		(at 8.750046 -48.653192 -90)
		(property "Reference" "C655"
			(at 0 0 270)
			(layer "F.SilkS")
			(hide yes)
			(effects
				(font
					(size 1.27 1.27)
				)
			)
		)
		(property "Value" "SC1KP50V2KX-1GP"
			(at 1.1811 -2.7051 270)
			(unlocked yes)
			(layer "F.Fab")
			(hide yes)
			(effects
				(font
					(size 1.016 1.016)
					(thickness 0.1524)
				)
			)
		)
		(property "Device Type" "C402H22"
			(at 1.1811 -4.2291 270)
			(unlocked yes)
			(layer "F.Fab")
			(hide yes)
			(effects
				(font
					(size 1.016 1.016)
					(thickness 0.1524)
				)
			)
		)
		(duplicate_pad_numbers_are_jumpers no)
		(fp_rect
			(start -0.4318 0.9525)
			(end 0.4318 -0.9525)
			(stroke
				(width 0)
				(type default)
			)
			(fill no)
			(layer "F.CrtYd")
		)
		(fp_rect
			(start -0.4318 0.9525)
			(end 0.4318 -0.9525)
			(stroke
				(width 0)
				(type default)
			)
			(fill no)
			(layer "F.Fab")
		)
		(pad "1" smd custom
			(at 0 -0.4445 270)
			(size 0.1524 0.1524)
			(layers "F.Cu" "F.Mask" "F.Paste")
			(net "MB0_TEMP")
			(options
				(clearance outline)
				(anchor circle)
			)
			(primitives
				(gr_poly
					(pts
						(arc
							(start 0.3048 -0.2032)
							(mid 0.275042 -0.275042)
							(end 0.2032 -0.3048)
						)
						(arc
							(start -0.2032 -0.3048)
							(mid -0.275042 -0.275042)
							(end -0.3048 -0.2032)
						)
						(arc
							(start -0.3048 0.2032)
							(mid -0.275042 0.275042)
							(end -0.2032 0.3048)
						)
						(arc
							(start 0.2032 0.3048)
							(mid 0.275042 0.275042)
							(end 0.3048 0.2032)
						)
					)
					(width 0)
					(fill yes)
				)
			)
		)
		(pad "2" smd custom
			(at 0 0.4445 270)
			(size 0.1524 0.1524)
			(layers "F.Cu" "F.Mask" "F.Paste")
			(net "GND")
			(options
				(clearance outline)
				(anchor circle)
			)
			(primitives
				(gr_poly
					(pts
						(arc
							(start 0.3048 -0.2032)
							(mid 0.275042 -0.275042)
							(end 0.2032 -0.3048)
						)
						(arc
							(start -0.2032 -0.3048)
							(mid -0.275042 -0.275042)
							(end -0.3048 -0.2032)
						)
						(arc
							(start -0.3048 0.2032)
							(mid -0.275042 0.275042)
							(end -0.2032 0.3048)
						)
						(arc
							(start 0.2032 0.3048)
							(mid 0.275042 0.275042)
							(end 0.3048 0.2032)
						)
					)
					(width 0)
					(fill yes)
				)
			)
		)
	)
	(footprint ""
		(layer "F.Cu")
		(at 92.583 -74.422 -90)
		(property "Reference" "R106"
			(at 0 0 270)
			(layer "F.SilkS")
			(hide yes)
			(effects
				(font
					(size 1.27 1.27)
				)
			)
		)
		(property "Value" "4K75R2F-1-GP"
			(at 0.064008 -3.993896 270)
			(unlocked yes)
			(layer "F.Fab")
			(hide yes)
			(effects
				(font
					(size 1.016 1.016)
					(thickness 0.1524)
				)
			)
		)
		(property "Device Type" "R402H16"
			(at 0.064008 -5.517896 270)
			(unlocked yes)
			(layer "F.Fab")
			(hide yes)
			(effects
				(font
					(size 1.016 1.016)
					(thickness 0.1524)
				)
			)
		)
		(duplicate_pad_numbers_are_jumpers no)
		(fp_line
			(start -0.508 -0.9398)
			(end -0.508 0.9398)
			(stroke
				(width 0.1524)
				(type default)
			)
			(layer "F.SilkS")
		)
		(fp_line
			(start 0.508 -0.9398)
			(end -0.508 -0.9398)
			(stroke
				(width 0.1524)
				(type default)
			)
			(layer "F.SilkS")
		)
		(fp_rect
			(start -0.508 0.9398)
			(end 0.508 -0.9398)
			(stroke
				(width 0)
				(type default)
			)
			(fill no)
			(layer "F.CrtYd")
		)
		(fp_rect
			(start -0.508 0.9398)
			(end 0.508 -0.9398)
			(stroke
				(width 0)
				(type default)
			)
			(fill no)
			(layer "F.Fab")
		)
		(pad "1" smd custom
			(at 0 -0.4445 270)
			(size 0.1397 0.1397)
			(layers "F.Cu" "F.Mask" "F.Paste")
			(net "LSI_T_N")
			(options
				(clearance outline)
				(anchor circle)
			)
			(primitives
				(gr_poly
					(pts
						(arc
							(start -0.1778 -0.2794)
							(mid -0.249642 -0.249642)
							(end -0.2794 -0.1778)
						)
						(arc
							(start -0.2794 0.1778)
							(mid -0.249642 0.249642)
							(end -0.1778 0.2794)
						)
						(arc
							(start 0.1778 0.2794)
							(mid 0.249642 0.249642)
							(end 0.2794 0.1778)
						)
						(arc
							(start 0.2794 -0.1778)
							(mid 0.249642 -0.249642)
							(end 0.1778 -0.2794)
						)
					)
					(width 0)
					(fill yes)
				)
			)
		)
		(pad "2" smd custom
			(at 0 0.4445 270)
			(size 0.1397 0.1397)
			(layers "F.Cu" "F.Mask" "F.Paste")
			(net "P1V8_E")
			(options
				(clearance outline)
				(anchor circle)
			)
			(primitives
				(gr_poly
					(pts
						(arc
							(start -0.1778 -0.2794)
							(mid -0.249642 -0.249642)
							(end -0.2794 -0.1778)
						)
						(arc
							(start -0.2794 0.1778)
							(mid -0.249642 0.249642)
							(end -0.1778 0.2794)
						)
						(arc
							(start 0.1778 0.2794)
							(mid 0.249642 0.249642)
							(end 0.2794 0.1778)
						)
						(arc
							(start 0.2794 -0.1778)
							(mid 0.249642 -0.249642)
							(end 0.1778 -0.2794)
						)
					)
					(width 0)
					(fill yes)
				)
			)
		)
	)
	(footprint ""
		(layer "F.Cu")
		(at 169.660062 -95.035878 90)
		(property "Reference" "U6"
			(at 0 0 90)
			(layer "F.SilkS")
			(hide yes)
			(effects
				(font
					(size 1.27 1.27)
				)
			)
		)
		(property "Value" "VT235WFQX-ADJ-1-GP"
			(at -5.8166 -7.7216 90)
			(unlocked yes)
			(layer "F.Fab")
			(hide yes)
			(effects
				(font
					(size 1.016 1.016)
					(thickness 0.1524)
				)
			)
		)
		(property "Device Type" "QFN19-1H40"
			(at -5.8166 -9.2456 90)
			(unlocked yes)
			(layer "F.Fab")
			(hide yes)
			(effects
				(font
					(size 1.016 1.016)
					(thickness 0.1524)
				)
			)
		)
		(duplicate_pad_numbers_are_jumpers no)
		(fp_line
			(start -1.4859 -3.0734)
			(end -2.7559 -3.0734)
			(stroke
				(width 0.1524)
				(type default)
			)
			(layer "F.SilkS")
		)
		(fp_line
			(start -2.7559 -3.0734)
			(end -2.7559 -1.8034)
			(stroke
				(width 0.1524)
				(type default)
			)
			(layer "F.SilkS")
		)
		(fp_line
			(start -1.253236 -2.821432)
			(end -1.253236 -3.329432)
			(stroke
				(width 0.1524)
				(type default)
			)
			(layer "F.SilkS")
		)
		(fp_line
			(start 2.821432 0.23876)
			(end 3.329432 0.23876)
			(stroke
				(width 0.1524)
				(type default)
			)
			(layer "F.SilkS")
		)
		(fp_line
			(start -2.7559 1.8034)
			(end -2.7559 3.0734)
			(stroke
				(width 0.1524)
				(type default)
			)
			(layer "F.SilkS")
		)
		(fp_line
			(start 0.766064 2.796032)
			(end 0.766064 3.558032)
			(stroke
				(width 0.1524)
				(type default)
			)
			(layer "F.SilkS")
		)
		(fp_line
			(start 3.0861 3.0734)
			(end 3.0861 1.8034)
			(stroke
				(width 0.1524)
				(type default)
			)
			(layer "F.SilkS")
		)
		(fp_line
			(start 1.8161 3.0734)
			(end 3.0861 3.0734)
			(stroke
				(width 0.1524)
				(type default)
			)
			(layer "F.SilkS")
		)
		(fp_line
			(start -2.7559 3.0734)
			(end -1.4859 3.0734)
			(stroke
				(width 0.1524)
				(type default)
			)
			(layer "F.SilkS")
		)
		(fp_poly
			(pts
				(xy 3.0861 -3.0734) (xy 1.8161 -3.0734) (xy 3.0861 -1.8034)
			)
			(stroke
				(width 0)
				(type default)
			)
			(fill yes)
			(layer "F.SilkS")
		)
		(fp_rect
			(start -2.2479 2.2479)
			(end 2.2479 -2.2479)
			(stroke
				(width 0)
				(type default)
			)
			(fill no)
			(layer "F.CrtYd")
		)
		(fp_poly
			(pts
				(xy -2.7559 -3.0734) (xy -2.7559 3.0734) (xy 3.0861 3.0734) (xy 3.0861 2.0193) (xy 2.2479 2.0193)
				(xy 2.2479 2.2479) (xy -2.2479 2.2479) (xy -2.2479 -2.2479) (xy 2.2479 -2.2479) (xy 2.2479 2.0066)
				(xy 3.0861 2.0066) (xy 3.0861 -3.0734)
			)
			(stroke
				(width 0)
				(type default)
			)
			(fill no)
			(layer "F.CrtYd")
		)
		(fp_rect
			(start -2.7559 3.0734)
			(end 3.0861 -3.0734)
			(stroke
				(width 0)
				(type default)
			)
			(fill no)
			(layer "F.Fab")
		)
		(pad "1" smd rect
			(at 1.249934 -2.135632 90)
			(size 0.3556 0.8382)
			(layers "F.Cu" "F.Mask" "F.Paste")
			(net "AGND_P0V975")
		)
		(pad "2" smd rect
			(at 0.750062 -2.135632 90)
			(size 0.3556 0.8382)
			(layers "F.Cu" "F.Mask" "F.Paste")
			(net "Net_126")
		)
		(pad "3" smd rect
			(at 0.249936 -2.135632 90)
			(size 0.3556 0.8382)
			(layers "F.Cu" "F.Mask" "F.Paste")
			(net "VT235_AVDD")
		)
		(pad "4" smd rect
			(at -0.249936 -0.687832 90)
			(size 0.3556 3.7338)
			(layers "F.Cu" "F.Mask" "F.Paste")
			(net "P12V_SYBY_VDD_U6")
		)
		(pad "5" smd rect
			(at -1.249934 -1.335532 90)
			(size 0.3556 2.4384)
			(layers "F.Cu" "F.Mask" "F.Paste")
			(net "GND")
		)
		(pad "6" smd rect
			(at -1.75006 1.335532 90)
			(size 0.3556 2.4384)
			(layers "F.Cu" "F.Mask" "F.Paste")
			(net "VT235_VX")
		)
		(pad "7" smd rect
			(at -0.750062 1.335532 90)
			(size 0.3556 2.4384)
			(layers "F.Cu" "F.Mask" "F.Paste")
			(net "VT235_VX")
		)
		(pad "8" smd rect
			(at -0.249936 2.135632 90)
			(size 0.3556 0.8382)
			(layers "F.Cu" "F.Mask" "F.Paste")
			(net "VT235_BST")
		)
		(pad "9" smd rect
			(at 0.249936 2.135632 90)
			(size 0.3556 0.8382)
			(layers "F.Cu" "F.Mask" "F.Paste")
			(net "VT235_VDDL")
		)
		(pad "10" smd rect
			(at 0.750062 2.135632 90)
			(size 0.3556 0.8382)
			(layers "F.Cu" "F.Mask" "F.Paste")
			(net "VT235_AVDD")
		)
		(pad "11" smd rect
			(at 1.249934 2.135632 90)
			(size 0.3556 0.8382)
			(layers "F.Cu" "F.Mask" "F.Paste")
			(net "VT235_VFB")
		)
		(pad "12" smd rect
			(at 2.135632 1.75006 90)
			(size 0.8382 0.3556)
			(layers "F.Cu" "F.Mask" "F.Paste")
			(net "VT235_PGIN")
		)
		(pad "13" smd rect
			(at 2.135632 1.249934 90)
			(size 0.8382 0.3556)
			(layers "F.Cu" "F.Mask" "F.Paste")
			(net "VT235_VDES")
		)
		(pad "14" smd rect
			(at 2.135632 0.750062 90)
			(size 0.8382 0.3556)
			(layers "F.Cu" "F.Mask" "F.Paste")
			(net "VT235_VREF")
		)
		(pad "15" smd rect
			(at 2.135632 0.249936 90)
			(size 0.8382 0.3556)
			(layers "F.Cu" "F.Mask" "F.Paste")
			(net "VT235_BIAS")
		)
		(pad "16" smd rect
			(at 2.135632 -0.249936 90)
			(size 0.8382 0.3556)
			(layers "F.Cu" "F.Mask" "F.Paste")
			(net "VT235_IMAX")
		)
		(pad "17" smd rect
			(at 2.135632 -0.750062 90)
			(size 0.8382 0.3556)
			(layers "F.Cu" "F.Mask" "F.Paste")
			(net "P0V975_STAT")
		)
		(pad "18" smd rect
			(at 2.135632 -1.249934 90)
			(size 0.8382 0.3556)
			(layers "F.Cu" "F.Mask" "F.Paste")
			(net "VT235_EN")
		)
		(pad "19" smd rect
			(at 2.135632 -1.75006 90)
			(size 0.8382 0.3556)
			(layers "F.Cu" "F.Mask" "F.Paste")
			(net "VT235_IRIP")
		)
	)
	(footprint ""
		(layer "F.Cu")
		(at 191.253872 -41.676574 -90)
		(property "Reference" "R175"
			(at 0 0 270)
			(layer "F.SilkS")
			(hide yes)
			(effects
				(font
					(size 1.27 1.27)
				)
			)
		)
		(property "Value" "10KR2F-2-GP"
			(at 0.064008 -3.993896 270)
			(unlocked yes)
			(layer "F.Fab")
			(hide yes)
			(effects
				(font
					(size 1.016 1.016)
					(thickness 0.1524)
				)
			)
		)
		(property "Device Type" "R402H16"
			(at 0.064008 -5.517896 270)
			(unlocked yes)
			(layer "F.Fab")
			(hide yes)
			(effects
				(font
					(size 1.016 1.016)
					(thickness 0.1524)
				)
			)
		)
		(duplicate_pad_numbers_are_jumpers no)
		(fp_line
			(start -0.508 -0.9398)
			(end -0.508 0.9398)
			(stroke
				(width 0.1524)
				(type default)
			)
			(layer "F.SilkS")
		)
		(fp_line
			(start 0.508 -0.9398)
			(end -0.508 -0.9398)
			(stroke
				(width 0.1524)
				(type default)
			)
			(layer "F.SilkS")
		)
		(fp_rect
			(start -0.508 0.9398)
			(end 0.508 -0.9398)
			(stroke
				(width 0)
				(type default)
			)
			(fill no)
			(layer "F.CrtYd")
		)
		(fp_rect
			(start -0.508 0.9398)
			(end 0.508 -0.9398)
			(stroke
				(width 0)
				(type default)
			)
			(fill no)
			(layer "F.Fab")
		)
		(pad "1" smd custom
			(at 0 -0.4445 270)
			(size 0.1397 0.1397)
			(layers "F.Cu" "F.Mask" "F.Paste")
			(net "GND")
			(options
				(clearance outline)
				(anchor circle)
			)
			(primitives
				(gr_poly
					(pts
						(arc
							(start -0.1778 -0.2794)
							(mid -0.249642 -0.249642)
							(end -0.2794 -0.1778)
						)
						(arc
							(start -0.2794 0.1778)
							(mid -0.249642 0.249642)
							(end -0.1778 0.2794)
						)
						(arc
							(start 0.1778 0.2794)
							(mid 0.249642 0.249642)
							(end 0.2794 0.1778)
						)
						(arc
							(start 0.2794 -0.1778)
							(mid 0.249642 -0.249642)
							(end 0.1778 -0.2794)
						)
					)
					(width 0)
					(fill yes)
				)
			)
		)
		(pad "2" smd custom
			(at 0 0.4445 270)
			(size 0.1397 0.1397)
			(layers "F.Cu" "F.Mask" "F.Paste")
			(net "IOC_CLK_SEL0")
			(options
				(clearance outline)
				(anchor circle)
			)
			(primitives
				(gr_poly
					(pts
						(arc
							(start -0.1778 -0.2794)
							(mid -0.249642 -0.249642)
							(end -0.2794 -0.1778)
						)
						(arc
							(start -0.2794 0.1778)
							(mid -0.249642 0.249642)
							(end -0.1778 0.2794)
						)
						(arc
							(start 0.1778 0.2794)
							(mid 0.249642 0.249642)
							(end 0.2794 0.1778)
						)
						(arc
							(start 0.2794 -0.1778)
							(mid 0.249642 -0.249642)
							(end 0.1778 -0.2794)
						)
					)
					(width 0)
					(fill yes)
				)
			)
		)
	)
)
